(kicad_pcb
	(version 20241229)
	(generator "pcbnew")
	(generator_version "9.0")
	(general
		(thickness 1.62)
		(legacy_teardrops no)
	)
	(paper "A4")
	(title_block
		(title "OCuLink to 10GbE adapter")
		(date "2026-02-23")
		(rev "1.1.0")
		(company "Antmicro Ltd")
		(comment 1 "www.antmicro.com")
		(comment 9 "footprints 446-450 of 510")
	)
	(layers
		(0 "F.Cu" signal)
		(4 "In1.Cu" signal)
		(6 "In2.Cu" signal)
		(8 "In3.Cu" signal)
		(10 "In4.Cu" signal)
		(12 "In5.Cu" signal)
		(14 "In6.Cu" signal)
		(2 "B.Cu" signal)
		(9 "F.Adhes" user "F.Adhesive")
		(11 "B.Adhes" user "B.Adhesive")
		(13 "F.Paste" user)
		(15 "B.Paste" user)
		(5 "F.SilkS" user "F.Silkscreen")
		(7 "B.SilkS" user "B.Silkscreen")
		(1 "F.Mask" user)
		(3 "B.Mask" user)
		(17 "Dwgs.User" user "User.Drawings")
		(19 "Cmts.User" user "User.Comments")
		(21 "Eco1.User" user "User.Eco1")
		(23 "Eco2.User" user "User.Eco2")
		(25 "Edge.Cuts" user)
		(27 "Margin" user)
		(31 "F.CrtYd" user "F.Courtyard")
		(29 "B.CrtYd" user "B.Courtyard")
		(35 "F.Fab" user)
		(33 "B.Fab" user)
	)
	(footprint "antmicro-footprints:R_0402_1005Metric"
		(layer "B.Cu")
		(at 74 96.65 180)
		(descr "Resistor SMD 0402")
		(tags "resistor SMD 0402")
		(property "Reference" "R97"
			(at 0.85 -0.45 0)
			(layer "B.SilkS")
			(effects
				(font
					(size 0.7 0.7)
					(thickness 0.15)
				)
				(justify left bottom mirror)
			)
		)
		(property "Value" "R_10k_0402"
			(at -1.011843 -1.772047 0)
			(layer "B.Fab")
			(hide yes)
			(effects
				(font
					(size 0.7 0.7)
					(thickness 0.15)
				)
				(justify left bottom mirror)
			)
		)
		(property "Datasheet" "https://www.bourns.com/docs/product-datasheets/cr.pdf"
			(at 0 0 0)
			(layer "B.Fab")
			(hide yes)
			(effects
				(font
					(size 1.27 1.27)
					(thickness 0.15)
				)
				(justify mirror)
			)
		)
		(property "Description" "SMD Chip Resistor, 10 kohm, ± 1%, 62.5 mW, 0402 [1005 Metric], Thick Film, General Purpose"
			(at 0 0 0)
			(layer "B.Fab")
			(hide yes)
			(effects
				(font
					(size 1.27 1.27)
					(thickness 0.15)
				)
				(justify mirror)
			)
		)
		(property "MPN" "CR0402-FX-1002GLF"
			(at 0 0 180)
			(unlocked yes)
			(layer "B.Fab")
			(hide yes)
			(effects
				(font
					(size 1 1)
					(thickness 0.15)
				)
				(justify mirror)
			)
		)
		(property "Manufacturer" "Bourns"
			(at 0 0 180)
			(unlocked yes)
			(layer "B.Fab")
			(hide yes)
			(effects
				(font
					(size 1 1)
					(thickness 0.15)
				)
				(justify mirror)
			)
		)
		(property "License" "Apache-2.0"
			(at 0 0 180)
			(unlocked yes)
			(layer "B.Fab")
			(hide yes)
			(effects
				(font
					(size 1 1)
					(thickness 0.15)
				)
				(justify mirror)
			)
		)
		(property "Author" "Antmicro"
			(at 0 0 180)
			(unlocked yes)
			(layer "B.Fab")
			(hide yes)
			(effects
				(font
					(size 1 1)
					(thickness 0.15)
				)
				(justify mirror)
			)
		)
		(property "Val" "10k"
			(at 0 0 180)
			(unlocked yes)
			(layer "B.Fab")
			(hide yes)
			(effects
				(font
					(size 1 1)
					(thickness 0.15)
				)
				(justify mirror)
			)
		)
		(property "Tolerance" "1%"
			(at 0 0 180)
			(unlocked yes)
			(layer "B.Fab")
			(hide yes)
			(effects
				(font
					(size 1 1)
					(thickness 0.15)
				)
				(justify mirror)
			)
		)
		(sheetname "/X710-AT2 Misc/")
		(sheetfile "x710-at2-mics.kicad_sch")
		(attr smd exclude_from_pos_files exclude_from_bom dnp)
		(fp_rect
			(start -0.925 0.47)
			(end 0.925 -0.47)
			(stroke
				(width 0.05)
				(type default)
			)
			(fill no)
			(layer "B.CrtYd")
		)
		(fp_rect
			(start -0.5 0.25)
			(end 0.5 -0.25)
			(stroke
				(width 0.15)
				(type solid)
			)
			(fill no)
			(layer "B.Fab")
		)
		(pad "1" smd roundrect
			(at -0.48 0 180)
			(size 0.59 0.64)
			(layers "B.Cu" "B.Mask" "B.Paste")
			(roundrect_rratio 0.25)
			(net 47 "/X710-AT2 Misc/POR_BYPASS")
			(pintype "passive")
		)
		(pad "2" smd roundrect
			(at 0.48 0 180)
			(size 0.59 0.64)
			(layers "B.Cu" "B.Mask" "B.Paste")
			(roundrect_rratio 0.25)
			(net 7 "+3V3")
			(pintype "passive")
		)
	)
	(footprint "antmicro-footprints:C_0402_1005Metric"
		(layer "B.Cu")
		(at 82.22 103.23 90)
		(descr "Capacitor SMD 0402")
		(tags "capacitor SMD 0402")
		(property "Reference" "C181"
			(at -11.62 -0.04 90)
			(layer "B.SilkS")
			(effects
				(font
					(size 0.7 0.7)
					(thickness 0.15)
				)
				(justify right top mirror)
			)
		)
		(property "Value" "C_1u_25V_0402"
			(at -1.022927 -2.155213 90)
			(layer "B.Fab")
			(hide yes)
			(effects
				(font
					(size 0.7 0.7)
					(thickness 0.15)
				)
				(justify right top mirror)
			)
		)
		(property "Datasheet" "https://www.murata.com/products/productdetail?partno=GRM155R61E105KE11%23"
			(at 0 0 90)
			(layer "B.Fab")
			(hide yes)
			(effects
				(font
					(size 1.27 1.27)
					(thickness 0.15)
				)
				(justify mirror)
			)
		)
		(property "Description" "SMD Multilayer Ceramic Capacitor, 1 µF, 25 V, 0402 [1005 Metric], ± 10%, X5R, GRM Series"
			(at 0 0 90)
			(layer "B.Fab")
			(hide yes)
			(effects
				(font
					(size 1.27 1.27)
					(thickness 0.15)
				)
				(justify mirror)
			)
		)
		(property "MPN" "GRM155R61E105KE11J"
			(at 0 0 90)
			(unlocked yes)
			(layer "B.Fab")
			(hide yes)
			(effects
				(font
					(size 1 1)
					(thickness 0.15)
				)
				(justify mirror)
			)
		)
		(property "Manufacturer" "Murata"
			(at 0 0 90)
			(unlocked yes)
			(layer "B.Fab")
			(hide yes)
			(effects
				(font
					(size 1 1)
					(thickness 0.15)
				)
				(justify mirror)
			)
		)
		(property "License" "Apache-2.0"
			(at 0 0 90)
			(unlocked yes)
			(layer "B.Fab")
			(hide yes)
			(effects
				(font
					(size 1 1)
					(thickness 0.15)
				)
				(justify mirror)
			)
		)
		(property "Author" "Antmicro"
			(at 0 0 90)
			(unlocked yes)
			(layer "B.Fab")
			(hide yes)
			(effects
				(font
					(size 1 1)
					(thickness 0.15)
				)
				(justify mirror)
			)
		)
		(property "Val" "1u"
			(at 0 0 90)
			(unlocked yes)
			(layer "B.Fab")
			(hide yes)
			(effects
				(font
					(size 1 1)
					(thickness 0.15)
				)
				(justify mirror)
			)
		)
		(property "Voltage" "25V"
			(at 0 0 90)
			(unlocked yes)
			(layer "B.Fab")
			(hide yes)
			(effects
				(font
					(size 1 1)
					(thickness 0.15)
				)
				(justify mirror)
			)
		)
		(property "Dielectric" "X5R"
			(at 0 0 90)
			(unlocked yes)
			(layer "B.Fab")
			(hide yes)
			(effects
				(font
					(size 1 1)
					(thickness 0.15)
				)
				(justify mirror)
			)
		)
		(sheetname "/X710-AT2 power/")
		(sheetfile "x710-at2-power.kicad_sch")
		(attr smd)
		(fp_rect
			(start -0.925 0.47)
			(end 0.925 -0.47)
			(stroke
				(width 0.05)
				(type default)
			)
			(fill no)
			(layer "B.CrtYd")
		)
		(fp_line
			(start 0.504 -0.248)
			(end -0.494 -0.248)
			(stroke
				(width 0.15)
				(type solid)
			)
			(layer "B.Fab")
		)
		(fp_line
			(start -0.494 -0.248)
			(end -0.494 0.25)
			(stroke
				(width 0.15)
				(type solid)
			)
			(layer "B.Fab")
		)
		(fp_line
			(start 0.504 0.25)
			(end 0.504 -0.248)
			(stroke
				(width 0.15)
				(type solid)
			)
			(layer "B.Fab")
		)
		(fp_line
			(start -0.494 0.25)
			(end 0.504 0.25)
			(stroke
				(width 0.15)
				(type solid)
			)
			(layer "B.Fab")
		)
		(pad "1" smd roundrect
			(at -0.48 0 90)
			(size 0.59 0.64)
			(layers "B.Cu" "B.Mask" "B.Paste")
			(roundrect_rratio 0.25)
			(net 28 "GND")
			(pintype "passive")
		)
		(pad "2" smd roundrect
			(at 0.48 0 90)
			(size 0.59 0.64)
			(layers "B.Cu" "B.Mask" "B.Paste")
			(roundrect_rratio 0.25)
			(net 12 "XFI_VDD")
			(pintype "passive")
		)
	)
	(footprint "antmicro-footprints:C_0402_1005Metric"
		(layer "B.Cu")
		(at 77.225 104.2 -90)
		(descr "Capacitor SMD 0402")
		(tags "capacitor SMD 0402")
		(property "Reference" "C104"
			(at 9 0.485 90)
			(layer "B.SilkS")
			(effects
				(font
					(size 0.7 0.7)
					(thickness 0.15)
				)
				(justify left bottom mirror)
			)
		)
		(property "Value" "C_1u_25V_0402"
			(at -1.022927 -2.155213 90)
			(layer "B.Fab")
			(hide yes)
			(effects
				(font
					(size 0.7 0.7)
					(thickness 0.15)
				)
				(justify left bottom mirror)
			)
		)
		(property "Datasheet" "https://www.murata.com/products/productdetail?partno=GRM155R61E105KE11%23"
			(at 0 0 90)
			(layer "B.Fab")
			(hide yes)
			(effects
				(font
					(size 1.27 1.27)
					(thickness 0.15)
				)
				(justify mirror)
			)
		)
		(property "Description" "SMD Multilayer Ceramic Capacitor, 1 µF, 25 V, 0402 [1005 Metric], ± 10%, X5R, GRM Series"
			(at 0 0 90)
			(layer "B.Fab")
			(hide yes)
			(effects
				(font
					(size 1.27 1.27)
					(thickness 0.15)
				)
				(justify mirror)
			)
		)
		(property "MPN" "GRM155R61E105KE11J"
			(at 0 0 270)
			(unlocked yes)
			(layer "B.Fab")
			(hide yes)
			(effects
				(font
					(size 1 1)
					(thickness 0.15)
				)
				(justify mirror)
			)
		)
		(property "Manufacturer" "Murata"
			(at 0 0 270)
			(unlocked yes)
			(layer "B.Fab")
			(hide yes)
			(effects
				(font
					(size 1 1)
					(thickness 0.15)
				)
				(justify mirror)
			)
		)
		(property "License" "Apache-2.0"
			(at 0 0 270)
			(unlocked yes)
			(layer "B.Fab")
			(hide yes)
			(effects
				(font
					(size 1 1)
					(thickness 0.15)
				)
				(justify mirror)
			)
		)
		(property "Author" "Antmicro"
			(at 0 0 270)
			(unlocked yes)
			(layer "B.Fab")
			(hide yes)
			(effects
				(font
					(size 1 1)
					(thickness 0.15)
				)
				(justify mirror)
			)
		)
		(property "Val" "1u"
			(at 0 0 270)
			(unlocked yes)
			(layer "B.Fab")
			(hide yes)
			(effects
				(font
					(size 1 1)
					(thickness 0.15)
				)
				(justify mirror)
			)
		)
		(property "Voltage" "25V"
			(at 0 0 270)
			(unlocked yes)
			(layer "B.Fab")
			(hide yes)
			(effects
				(font
					(size 1 1)
					(thickness 0.15)
				)
				(justify mirror)
			)
		)
		(property "Dielectric" "X5R"
			(at 0 0 270)
			(unlocked yes)
			(layer "B.Fab")
			(hide yes)
			(effects
				(font
					(size 1 1)
					(thickness 0.15)
				)
				(justify mirror)
			)
		)
		(sheetname "/X710-AT2 power/")
		(sheetfile "x710-at2-power.kicad_sch")
		(attr smd)
		(fp_rect
			(start -0.925 0.47)
			(end 0.925 -0.47)
			(stroke
				(width 0.05)
				(type default)
			)
			(fill no)
			(layer "B.CrtYd")
		)
		(fp_line
			(start -0.494 0.25)
			(end 0.504 0.25)
			(stroke
				(width 0.15)
				(type solid)
			)
			(layer "B.Fab")
		)
		(fp_line
			(start 0.504 0.25)
			(end 0.504 -0.248)
			(stroke
				(width 0.15)
				(type solid)
			)
			(layer "B.Fab")
		)
		(fp_line
			(start -0.494 -0.248)
			(end -0.494 0.25)
			(stroke
				(width 0.15)
				(type solid)
			)
			(layer "B.Fab")
		)
		(fp_line
			(start 0.504 -0.248)
			(end -0.494 -0.248)
			(stroke
				(width 0.15)
				(type solid)
			)
			(layer "B.Fab")
		)
		(pad "1" smd roundrect
			(at -0.48 0 270)
			(size 0.59 0.64)
			(layers "B.Cu" "B.Mask" "B.Paste")
			(roundrect_rratio 0.25)
			(net 28 "GND")
			(pintype "passive")
		)
		(pad "2" smd roundrect
			(at 0.48 0 270)
			(size 0.59 0.64)
			(layers "B.Cu" "B.Mask" "B.Paste")
			(roundrect_rratio 0.25)
			(net 18 "+1V88")
			(pintype "passive")
		)
	)
	(footprint "antmicro-footprints:R_0402_1005Metric"
		(layer "B.Cu")
		(at 84.225 94.6 90)
		(descr "Resistor SMD 0402")
		(tags "resistor SMD 0402")
		(property "Reference" "R135"
			(at 12.5 -0.462343 90)
			(layer "B.SilkS")
			(effects
				(font
					(size 0.7 0.7)
					(thickness 0.15)
				)
				(justify right top mirror)
			)
		)
		(property "Value" "R_100R_0402"
			(at -1.011843 -1.772046 90)
			(layer "B.Fab")
			(hide yes)
			(effects
				(font
					(size 0.7 0.7)
					(thickness 0.15)
				)
				(justify right top mirror)
			)
		)
		(property "Datasheet" "https://www.bourns.com/docs/product-datasheets/cr.pdf"
			(at 0 0 90)
			(layer "B.Fab")
			(hide yes)
			(effects
				(font
					(size 1.27 1.27)
					(thickness 0.15)
				)
				(justify mirror)
			)
		)
		(property "Description" "SMD Chip Resistor, 100 ohm, ± 1%, 62.5 mW, 0402 [1005 Metric], Thick Film, General Purpose"
			(at 0 0 90)
			(layer "B.Fab")
			(hide yes)
			(effects
				(font
					(size 1.27 1.27)
					(thickness 0.15)
				)
				(justify mirror)
			)
		)
		(property "MPN" "CR0402-FX-1000GLF"
			(at 0 0 90)
			(unlocked yes)
			(layer "B.Fab")
			(hide yes)
			(effects
				(font
					(size 1 1)
					(thickness 0.15)
				)
				(justify mirror)
			)
		)
		(property "Manufacturer" "Bourns"
			(at 0 0 90)
			(unlocked yes)
			(layer "B.Fab")
			(hide yes)
			(effects
				(font
					(size 1 1)
					(thickness 0.15)
				)
				(justify mirror)
			)
		)
		(property "License" "Apache-2.0"
			(at 0 0 90)
			(unlocked yes)
			(layer "B.Fab")
			(hide yes)
			(effects
				(font
					(size 1 1)
					(thickness 0.15)
				)
				(justify mirror)
			)
		)
		(property "Author" "Antmicro"
			(at 0 0 90)
			(unlocked yes)
			(layer "B.Fab")
			(hide yes)
			(effects
				(font
					(size 1 1)
					(thickness 0.15)
				)
				(justify mirror)
			)
		)
		(property "Val" "100R"
			(at 0 0 90)
			(unlocked yes)
			(layer "B.Fab")
			(hide yes)
			(effects
				(font
					(size 1 1)
					(thickness 0.15)
				)
				(justify mirror)
			)
		)
		(property "Tolerance" "1%"
			(at 0 0 90)
			(unlocked yes)
			(layer "B.Fab")
			(hide yes)
			(effects
				(font
					(size 1 1)
					(thickness 0.15)
				)
				(justify mirror)
			)
		)
		(sheetname "/X710-AT2 RSVD/")
		(sheetfile "x710-at2-rsvd.kicad_sch")
		(attr smd)
		(fp_rect
			(start -0.925 0.47)
			(end 0.925 -0.47)
			(stroke
				(width 0.05)
				(type default)
			)
			(fill no)
			(layer "B.CrtYd")
		)
		(fp_rect
			(start -0.5 0.25)
			(end 0.5 -0.25)
			(stroke
				(width 0.15)
				(type solid)
			)
			(fill no)
			(layer "B.Fab")
		)
		(pad "1" smd roundrect
			(at -0.48 0 90)
			(size 0.59 0.64)
			(layers "B.Cu" "B.Mask" "B.Paste")
			(roundrect_rratio 0.25)
			(net 28 "GND")
			(pintype "passive")
		)
		(pad "2" smd roundrect
			(at 0.48 0 90)
			(size 0.59 0.64)
			(layers "B.Cu" "B.Mask" "B.Paste")
			(roundrect_rratio 0.25)
			(net 123 "/X710-AT2 RSVD/RSVDY22_VSS")
			(pintype "passive")
		)
	)
	(footprint "antmicro-footprints:FB_0603_1608Metric"
		(layer "B.Cu")
		(at 85 127.8 -90)
		(property "Reference" "FB1"
			(at -1 -1.6 90)
			(layer "B.SilkS")
			(effects
				(font
					(size 0.7 0.7)
					(thickness 0.15)
				)
				(justify left bottom mirror)
			)
		)
		(property "Value" "FB_33Z_3A_Murata-BLM18PG_0603"
			(at 0 -1.5 90)
			(layer "B.Fab")
			(hide yes)
			(effects
				(font
					(size 0.7 0.7)
					(thickness 0.15)
				)
				(justify left bottom mirror)
			)
		)
		(property "Datasheet" "https://www.murata.com/products/productdata/8796737273886/QNFA9101.pdf?1649080818000"
			(at 0 0 90)
			(layer "B.Fab")
			(hide yes)
			(effects
				(font
					(size 1.27 1.27)
					(thickness 0.15)
				)
				(justify mirror)
			)
		)
		(property "Description" "Ferrite Bead, 0603 [1608 Metric], 33 ohm, 3 A, BLM18PG, 0.025 ohm, ± 25%, DC power line"
			(at 0 0 90)
			(layer "B.Fab")
			(hide yes)
			(effects
				(font
					(size 1.27 1.27)
					(thickness 0.15)
				)
				(justify mirror)
			)
		)
		(property "Val" "33Z/3A"
			(at 0 0 270)
			(unlocked yes)
			(layer "B.Fab")
			(hide yes)
			(effects
				(font
					(size 1 1)
					(thickness 0.15)
				)
				(justify mirror)
			)
		)
		(property "MPN" "BLM18PG330SH1D"
			(at 0 0 270)
			(unlocked yes)
			(layer "B.Fab")
			(hide yes)
			(effects
				(font
					(size 1 1)
					(thickness 0.15)
				)
				(justify mirror)
			)
		)
		(property "Manufacturer" "Murata"
			(at 0 0 270)
			(unlocked yes)
			(layer "B.Fab")
			(hide yes)
			(effects
				(font
					(size 1 1)
					(thickness 0.15)
				)
				(justify mirror)
			)
		)
		(property "Current" ""
			(at 0 0 270)
			(unlocked yes)
			(layer "B.Fab")
			(hide yes)
			(effects
				(font
					(size 1 1)
					(thickness 0.15)
				)
				(justify mirror)
			)
		)
		(property "Author" "Antmicro"
			(at 0 0 270)
			(unlocked yes)
			(layer "B.Fab")
			(hide yes)
			(effects
				(font
					(size 1 1)
					(thickness 0.15)
				)
				(justify mirror)
			)
		)
		(property "License" "Apache-2.0"
			(at 0 0 270)
			(unlocked yes)
			(layer "B.Fab")
			(hide yes)
			(effects
				(font
					(size 1 1)
					(thickness 0.15)
				)
				(justify mirror)
			)
		)
		(sheetname "/2xRJ45/")
		(sheetfile "2xrj45.kicad_sch")
		(attr smd)
		(fp_line
			(start -0.15 0.4)
			(end 0.15 0.4)
			(stroke
				(width 0.15)
				(type solid)
			)
			(layer "B.SilkS")
		)
		(fp_line
			(start -0.15 -0.4)
			(end 0.15 -0.4)
			(stroke
				(width 0.15)
				(type solid)
			)
			(layer "B.SilkS")
		)
		(fp_rect
			(start -1.25 0.65)
			(end 1.25 -0.65)
			(stroke
				(width 0.05)
				(type solid)
			)
			(fill no)
			(layer "B.CrtYd")
		)
		(fp_line
			(start 0.8 0.408)
			(end -0.803 0.408)
			(stroke
				(width 0.15)
				(type solid)
			)
			(layer "B.Fab")
		)
		(fp_line
			(start 0.8 0.408)
			(end 0.8 -0.406)
			(stroke
				(width 0.15)
				(type solid)
			)
			(layer "B.Fab")
		)
		(fp_line
			(start -0.803 -0.406)
			(end -0.803 0.408)
			(stroke
				(width 0.15)
				(type solid)
			)
			(layer "B.Fab")
		)
		(fp_line
			(start 0.8 -0.406)
			(end -0.803 -0.406)
			(stroke
				(width 0.15)
				(type solid)
			)
			(layer "B.Fab")
		)
		(pad "1" smd roundrect
			(at -0.7 0 270)
			(size 0.8 1)
			(layers "B.Cu" "B.Mask" "B.Paste")
			(roundrect_rratio 0.2)
			(net 18 "+1V88")
			(pintype "passive")
		)
		(pad "2" smd roundrect
			(at 0.7 0 270)
			(size 0.8 1)
			(layers "B.Cu" "B.Mask" "B.Paste")
			(roundrect_rratio 0.2)
			(net 301 "+1V88_CT")
			(pintype "passive")
		)
	)
)
